# BASEBOARD_FAB2 (Tioga Pass) — schematic netlist excerpt (pin names and nets, part order shuffled) for the footprints in the layout excerpt that follows; sources: Cadence DE-HDL packaged netlist, KiCad conversion of Wiwynn_Tioga_Pass_MB.brd

EU1C2  PXE1610B  IC  pkg QFN  page 206
  BPWM1  = VR_PVSA_CPU1_PWM
  APWM6  = NC
  APWM5  = VR_PVCCIN_CPU1_PWM5
  APWM4  = VR_PVCCIN_CPU1_PWM4
  APWM3  = VR_PVCCIN_CPU1_PWM3
  APWM2  = VR_PVCCIN_CPU1_PWM2
  APWM1  = VR_PVCCIN_CPU1_PWM1
  SDA  = SMB_VR_STBY_LVC3_SDA
  SCL  = SMB_VR_STBY_LVC3_SCL
  RESET_N  = NC
  AVRRDY  = VR_VRRDY_PVCCIN_CPU1
  AVREN  = VR_PVCCIN_CPU1_VREN
  VRHOT_N  = IRQ_PVCCIN_CPU1_VRHOT_LVC3_R_N
  PINALRT_N  = FM_PVCCIN_CPU1_PWR_IN_ALERT_N
  MP0  = PWRGD_PVSA_CPU1_R
  MP1  = NC
  VCLK  = SVID_VCLK_PVCCIN_CPU1
  VDIO  = SVID_VDIO_PVCCIN_CPU1
  VALRT_N  = SVID_VALERT_VCCIN_CPU1
  MP2  = PU_VR_PVCCIN_CPU1_FLT1_SMBALT_N
  AVSEN  = VSENSE_PVCCIN_CPU1_AVSP
  AVREF  = VSENSE_PVCCIN_CPU1_N
  AIREF1  = VR_PVCCIN_CPU1_AIREF1
  AISEN1  = ISENSE_PVCCIN_CPU1_PH1_IMON
  AIREF2  = VR_PVCCIN_CPU1_AIREF2
  AISEN2  = ISENSE_PVCCIN_CPU1_PH2_IMON
  AIREF3  = VR_PVCCIN_CPU1_AIREF3
  AISEN3  = ISENSE_PVCCIN_CPU1_PH3_IMON
  AIREF4  = VR_PVCCIN_CPU1_AIREF4
  AISEN4  = ISENSE_PVCCIN_CPU1_PH4_IMON
  AIREF5  = VR_PVCCIN_CPU1_AIREF5
  AISEN5  = ISENSE_PVCCIN_CPU1_PH5_IMON
  AIREF6  = NC
  AISEN6  = NC
  BVSEN  = VSENSE_PVSA_CPU1_BVSP
  BVREF  = VSENSE_PVSA_CPU1_N
  BIREF1  = VR_PVSA_CPU1_BIREF1
  BISEN1  = ISENSE_PVSA_CPU1_IMON
  MP3  = PU_VR_PVCCIN_CPU1_IMON
  MP4  = NC
  XADDR2  = VR_PVCCIN_CPU1_XADDR2
  BTSEN  = A_TSENSE_PVSA_CPU1
  ATSEN  = A_TSENSE_PVCCIN_CPU1
  XADDR1  = VR_PVCCIN_CPU1_XADDR1
  VINSEN  = VR_PVCCIN_CPU1_AVINSEN
  IINSEN  = NC
  VDD  = VR_PVCCIN_CPU1_VDD
  VD12  = VR_PVCCIN_CPU1_VD12
  THPAD  = GND

(kicad_pcb
	(version 20260206)
	(generator "pcbnew")
	(generator_version "10.0")
	(general
		(thickness 1.6)
		(legacy_teardrops no)
	)
	(paper "A4")
	(title_block
		(title "Wiwynn_Tioga_Pass_MB.brd")
		(comment 1 "Tioga Pass / footprint 241 of 4770 (EU1C2), pads 18-34 of 49")
	)
	(layers
		(0 "F.Cu" signal "TOP")
		(4 "In1.Cu" signal "L2GND")
		(6 "In2.Cu" signal "L3")
		(8 "In3.Cu" signal "L4GND")
		(10 "In4.Cu" signal "L5")
		(12 "In5.Cu" signal "L6GND")
		(14 "In6.Cu" signal "L7VCC")
		(16 "In7.Cu" signal "L8VCC")
		(18 "In8.Cu" signal "L9GND")
		(20 "In9.Cu" signal "L10")
		(22 "In10.Cu" signal "L11GND")
		(24 "In11.Cu" signal "L12")
		(26 "In12.Cu" signal "L13GND")
		(2 "B.Cu" signal "BOTTOM")
		(9 "F.Adhes" user "F.Adhesive")
		(11 "B.Adhes" user "B.Adhesive")
		(13 "F.Paste" user "Package Geometry/Pastemask Top")
		(15 "B.Paste" user "Package Geometry/Pastemask Bottom")
		(5 "F.SilkS" user "Ref Des/Silkscreen Top")
		(7 "B.SilkS" user "Ref Des/Silkscreen Bottom")
		(1 "F.Mask" user "Board Geometry/Soldermask Top")
		(3 "B.Mask" user "Board Geometry/Soldermask Bottom")
		(17 "Dwgs.User" user "User.Drawings")
		(19 "Cmts.User" user "User.Comments")
		(21 "Eco1.User" user "User.Eco1")
		(23 "Eco2.User" user "User.Eco2")
		(25 "Edge.Cuts" user "Board Geometry/Outline")
		(27 "Margin" user)
		(31 "F.CrtYd" user "Package Geometry/Place Bound Top")
		(29 "B.CrtYd" user "Package Geometry/Place Bound Bottom")
		(35 "F.Fab" user "Ref Des/Assembly Top")
		(33 "B.Fab" user "Ref Des/Assembly Bottom")
	)
	(footprint ""
		(layer "F.Cu")
		(at 19.431 -92.456)
		(property "Reference" "EU1C2"
			(at -7.8232 -3.45313 0)
			(unlocked yes)
			(layer "F.SilkS")
			(effects
				(font
					(size 0.7874 0.5842)
					(thickness 0.1524)
				)
				(justify left)
			)
		)
		(property "Value" ""
			(at 0 0 0)
			(layer "F.Fab")
			(effects
				(font
					(size 1.27 1.27)
				)
			)
		)
		(duplicate_pad_numbers_are_jumpers no)
		(pad "18" smd custom
			(at -0.199898 2.8956)
			(size 0.0508 0.0508)
			(layers "F.Cu" "F.Mask" "F.Paste")
			(net "SVID_VDIO_PVCCIN_CPU1")
			(options
				(clearance outline)
				(anchor circle)
			)
			(primitives
				(gr_poly
					(pts
						(arc
							(start -0.1016 -0.254)
							(mid 0 -0.3556)
							(end 0.1016 -0.254)
						)
						(xy 0.1016 0.3556) (xy -0.1016 0.3556)
					)
					(width 0)
					(fill yes)
				)
			)
		)
		(pad "19" smd custom
			(at 0.199898 2.8956)
			(size 0.0508 0.0508)
			(layers "F.Cu" "F.Mask" "F.Paste")
			(net "SVID_VALERT_VCCIN_CPU1")
			(options
				(clearance outline)
				(anchor circle)
			)
			(primitives
				(gr_poly
					(pts
						(arc
							(start -0.1016 -0.254)
							(mid 0 -0.3556)
							(end 0.1016 -0.254)
						)
						(xy 0.1016 0.3556) (xy -0.1016 0.3556)
					)
					(width 0)
					(fill yes)
				)
			)
		)
		(pad "20" smd custom
			(at 0.599948 2.8956)
			(size 0.0508 0.0508)
			(layers "F.Cu" "F.Mask" "F.Paste")
			(net "PU_VR_PVCCIN_CPU1_FLT1_SMBALT_N")
			(options
				(clearance outline)
				(anchor circle)
			)
			(primitives
				(gr_poly
					(pts
						(arc
							(start -0.1016 -0.254)
							(mid 0 -0.3556)
							(end 0.1016 -0.254)
						)
						(xy 0.1016 0.3556) (xy -0.1016 0.3556)
					)
					(width 0)
					(fill yes)
				)
			)
		)
		(pad "21" smd custom
			(at 0.999998 2.8956)
			(size 0.0508 0.0508)
			(layers "F.Cu" "F.Mask" "F.Paste")
			(net "VSENSE_PVCCIN_CPU1_AVSP")
			(options
				(clearance outline)
				(anchor circle)
			)
			(primitives
				(gr_poly
					(pts
						(arc
							(start -0.1016 -0.254)
							(mid 0 -0.3556)
							(end 0.1016 -0.254)
						)
						(xy 0.1016 0.3556) (xy -0.1016 0.3556)
					)
					(width 0)
					(fill yes)
				)
			)
		)
		(pad "22" smd custom
			(at 1.400048 2.8956)
			(size 0.0508 0.0508)
			(layers "F.Cu" "F.Mask" "F.Paste")
			(net "VSENSE_PVCCIN_CPU1_N")
			(options
				(clearance outline)
				(anchor circle)
			)
			(primitives
				(gr_poly
					(pts
						(arc
							(start -0.1016 -0.254)
							(mid 0 -0.3556)
							(end 0.1016 -0.254)
						)
						(xy 0.1016 0.3556) (xy -0.1016 0.3556)
					)
					(width 0)
					(fill yes)
				)
			)
		)
		(pad "23" smd custom
			(at 1.800098 2.8956)
			(size 0.0508 0.0508)
			(layers "F.Cu" "F.Mask" "F.Paste")
			(net "VR_PVCCIN_CPU1_AIREF1")
			(options
				(clearance outline)
				(anchor circle)
			)
			(primitives
				(gr_poly
					(pts
						(arc
							(start -0.1016 -0.254)
							(mid 0 -0.3556)
							(end 0.1016 -0.254)
						)
						(xy 0.1016 0.3556) (xy -0.1016 0.3556)
					)
					(width 0)
					(fill yes)
				)
			)
		)
		(pad "24" smd custom
			(at 2.199894 2.8956)
			(size 0.0508 0.0508)
			(layers "F.Cu" "F.Mask" "F.Paste")
			(net "ISENSE_PVCCIN_CPU1_PH1_IMON")
			(options
				(clearance outline)
				(anchor circle)
			)
			(primitives
				(gr_poly
					(pts
						(arc
							(start -0.1016 -0.254)
							(mid 0 -0.3556)
							(end 0.1016 -0.254)
						)
						(xy 0.1016 0.3556) (xy -0.1016 0.3556)
					)
					(width 0)
					(fill yes)
				)
			)
		)
		(pad "25" smd custom
			(at 2.8956 2.199894)
			(size 0.0508 0.0508)
			(layers "F.Cu" "F.Mask" "F.Paste")
			(net "VR_PVCCIN_CPU1_AIREF2")
			(options
				(clearance outline)
				(anchor circle)
			)
			(primitives
				(gr_poly
					(pts
						(arc
							(start -0.254 0.1016)
							(mid -0.3556 0)
							(end -0.254 -0.1016)
						)
						(xy 0.3556 -0.1016) (xy 0.3556 0.1016)
					)
					(width 0)
					(fill yes)
				)
			)
		)
		(pad "26" smd custom
			(at 2.8956 1.800098)
			(size 0.0508 0.0508)
			(layers "F.Cu" "F.Mask" "F.Paste")
			(net "ISENSE_PVCCIN_CPU1_PH2_IMON")
			(options
				(clearance outline)
				(anchor circle)
			)
			(primitives
				(gr_poly
					(pts
						(arc
							(start -0.254 0.1016)
							(mid -0.3556 0)
							(end -0.254 -0.1016)
						)
						(xy 0.3556 -0.1016) (xy 0.3556 0.1016)
					)
					(width 0)
					(fill yes)
				)
			)
		)
		(pad "27" smd custom
			(at 2.8956 1.400048)
			(size 0.0508 0.0508)
			(layers "F.Cu" "F.Mask" "F.Paste")
			(net "VR_PVCCIN_CPU1_AIREF3")
			(options
				(clearance outline)
				(anchor circle)
			)
			(primitives
				(gr_poly
					(pts
						(arc
							(start -0.254 0.1016)
							(mid -0.3556 0)
							(end -0.254 -0.1016)
						)
						(xy 0.3556 -0.1016) (xy 0.3556 0.1016)
					)
					(width 0)
					(fill yes)
				)
			)
		)
		(pad "28" smd custom
			(at 2.8956 0.999998)
			(size 0.0508 0.0508)
			(layers "F.Cu" "F.Mask" "F.Paste")
			(net "ISENSE_PVCCIN_CPU1_PH3_IMON")
			(options
				(clearance outline)
				(anchor circle)
			)
			(primitives
				(gr_poly
					(pts
						(arc
							(start -0.254 0.1016)
							(mid -0.3556 0)
							(end -0.254 -0.1016)
						)
						(xy 0.3556 -0.1016) (xy 0.3556 0.1016)
					)
					(width 0)
					(fill yes)
				)
			)
		)
		(pad "29" smd custom
			(at 2.8956 0.599948)
			(size 0.0508 0.0508)
			(layers "F.Cu" "F.Mask" "F.Paste")
			(net "VR_PVCCIN_CPU1_AIREF4")
			(options
				(clearance outline)
				(anchor circle)
			)
			(primitives
				(gr_poly
					(pts
						(arc
							(start -0.254 0.1016)
							(mid -0.3556 0)
							(end -0.254 -0.1016)
						)
						(xy 0.3556 -0.1016) (xy 0.3556 0.1016)
					)
					(width 0)
					(fill yes)
				)
			)
		)
		(pad "30" smd custom
			(at 2.8956 0.199898)
			(size 0.0508 0.0508)
			(layers "F.Cu" "F.Mask" "F.Paste")
			(net "ISENSE_PVCCIN_CPU1_PH4_IMON")
			(options
				(clearance outline)
				(anchor circle)
			)
			(primitives
				(gr_poly
					(pts
						(arc
							(start -0.254 0.1016)
							(mid -0.3556 0)
							(end -0.254 -0.1016)
						)
						(xy 0.3556 -0.1016) (xy 0.3556 0.1016)
					)
					(width 0)
					(fill yes)
				)
			)
		)
		(pad "31" smd custom
			(at 2.8956 -0.199898)
			(size 0.0508 0.0508)
			(layers "F.Cu" "F.Mask" "F.Paste")
			(net "VR_PVCCIN_CPU1_AIREF5")
			(options
				(clearance outline)
				(anchor circle)
			)
			(primitives
				(gr_poly
					(pts
						(arc
							(start -0.254 0.1016)
							(mid -0.3556 0)
							(end -0.254 -0.1016)
						)
						(xy 0.3556 -0.1016) (xy 0.3556 0.1016)
					)
					(width 0)
					(fill yes)
				)
			)
		)
		(pad "32" smd custom
			(at 2.8956 -0.599948)
			(size 0.0508 0.0508)
			(layers "F.Cu" "F.Mask" "F.Paste")
			(net "ISENSE_PVCCIN_CPU1_PH5_IMON")
			(options
				(clearance outline)
				(anchor circle)
			)
			(primitives
				(gr_poly
					(pts
						(arc
							(start -0.254 0.1016)
							(mid -0.3556 0)
							(end -0.254 -0.1016)
						)
						(xy 0.3556 -0.1016) (xy 0.3556 0.1016)
					)
					(width 0)
					(fill yes)
				)
			)
		)
		(pad "33" smd custom
			(at 2.8956 -0.999998)
			(size 0.0508 0.0508)
			(layers "F.Cu" "F.Mask" "F.Paste")
			(net "Net_276")
			(options
				(clearance outline)
				(anchor circle)
			)
			(primitives
				(gr_poly
					(pts
						(arc
							(start -0.254 0.1016)
							(mid -0.3556 0)
							(end -0.254 -0.1016)
						)
						(xy 0.3556 -0.1016) (xy 0.3556 0.1016)
					)
					(width 0)
					(fill yes)
				)
			)
		)
		(pad "34" smd custom
			(at 2.8956 -1.400048)
			(size 0.0508 0.0508)
			(layers "F.Cu" "F.Mask" "F.Paste")
			(net "Net_291")
			(options
				(clearance outline)
				(anchor circle)
			)
			(primitives
				(gr_poly
					(pts
						(arc
							(start -0.254 0.1016)
							(mid -0.3556 0)
							(end -0.254 -0.1016)
						)
						(xy 0.3556 -0.1016) (xy 0.3556 0.1016)
					)
					(width 0)
					(fill yes)
				)
			)
		)
	)
)
